# S9S_MB_2U (Grand Teton) — schematic netlist excerpt (pin names and nets, part order shuffled) for the footprints in the layout excerpt that follows; sources: Cadence DE-HDL packaged netlist, KiCad conversion of 03242023_DA0F0TMBIJ0_F0T_Motherboard_J_brd_V01_OCP.brd

R2451  Q_RES  10K 1% EMPTY  pkg 0402LF  page 202 : A = P3V3_AUX ; B = FM_ESPI_PLD_R1_EN
C301  Q_CAP  22UF 4V 20% X6S  pkg C0402  page 77 : A = PVCCIN_CPU1 ; B = GND

(kicad_pcb
	(version 20260206)
	(generator "pcbnew")
	(generator_version "10.0")
	(general
		(thickness 1.6)
		(legacy_teardrops no)
	)
	(paper "A4")
	(title_block
		(title "03242023_DA0F0TMBIJ0_F0T_Motherboard_J_brd_V01_OCP.brd")
		(comment 1 "Grand Teton / footprints 3016-3017 of 6105")
	)
	(layers
		(0 "F.Cu" signal "TOP")
		(4 "In1.Cu" signal "GND")
		(6 "In2.Cu" signal "IN1")
		(8 "In3.Cu" signal "GND1")
		(10 "In4.Cu" signal "IN2")
		(12 "In5.Cu" signal "GND2")
		(14 "In6.Cu" signal "IN3")
		(16 "In7.Cu" signal "GND3")
		(18 "In8.Cu" signal "VCC")
		(20 "In9.Cu" signal "VCC1")
		(22 "In10.Cu" signal "GND4")
		(24 "In11.Cu" signal "IN4")
		(26 "In12.Cu" signal "GND5")
		(28 "In13.Cu" signal "IN5")
		(30 "In14.Cu" signal "GND6")
		(32 "In15.Cu" signal "IN6")
		(34 "In16.Cu" signal "GND7")
		(2 "B.Cu" signal "BOTTOM")
		(9 "F.Adhes" user "F.Adhesive")
		(11 "B.Adhes" user "B.Adhesive")
		(13 "F.Paste" user "Package Geometry/Pastemask Top")
		(15 "B.Paste" user "Package Geometry/Pastemask Bottom")
		(5 "F.SilkS" user "Ref Des/Silkscreen Top")
		(7 "B.SilkS" user "Ref Des/Silkscreen Bottom")
		(1 "F.Mask" user "Board Geometry/Soldermask Top")
		(3 "B.Mask" user "Board Geometry/Soldermask Bottom")
		(17 "Dwgs.User" user "User.Drawings")
		(19 "Cmts.User" user "User.Comments")
		(21 "Eco1.User" user "User.Eco1")
		(23 "Eco2.User" user "User.Eco2")
		(25 "Edge.Cuts" user "Board Geometry/Outline")
		(27 "Margin" user)
		(31 "F.CrtYd" user "Package Geometry/Place Bound Top")
		(29 "B.CrtYd" user "Package Geometry/Place Bound Bottom")
		(35 "F.Fab" user "Ref Des/Assembly Top")
		(33 "B.Fab" user "Ref Des/Assembly Bottom")
	)
	(footprint ""
		(layer "F.Cu")
		(at 117.526816 -255.0541 90)
		(property "Reference" "C301"
			(at 0 0 90)
			(layer "F.SilkS")
			(hide yes)
			(effects
				(font
					(size 1.27 1.27)
				)
			)
		)
		(property "Value" ""
			(at 0 0 90)
			(layer "F.Fab")
			(effects
				(font
					(size 1.27 1.27)
				)
			)
		)
		(duplicate_pad_numbers_are_jumpers no)
		(fp_line
			(start 0.7874 -0.4064)
			(end 0.7874 0.4064)
			(stroke
				(width 0.1524)
				(type default)
			)
			(layer "F.SilkS")
		)
		(fp_line
			(start -0.7874 -0.4064)
			(end 0.7874 -0.4064)
			(stroke
				(width 0.1524)
				(type default)
			)
			(layer "F.SilkS")
		)
		(fp_line
			(start 0.7874 0.4064)
			(end -0.7874 0.4064)
			(stroke
				(width 0.1524)
				(type default)
			)
			(layer "F.SilkS")
		)
		(fp_line
			(start -0.7874 0.4064)
			(end -0.7874 -0.4064)
			(stroke
				(width 0.1524)
				(type default)
			)
			(layer "F.SilkS")
		)
		(fp_line
			(start -0.12065 -0.305054)
			(end -0.12065 -0.2794)
			(stroke
				(width 0.1)
				(type default)
			)
			(layer "F.Fab")
		)
		(fp_line
			(start -0.67945 -0.305054)
			(end -0.12065 -0.305054)
			(stroke
				(width 0.1)
				(type default)
			)
			(layer "F.Fab")
		)
		(fp_line
			(start 0.67945 -0.3048)
			(end 0.67945 0.3048)
			(stroke
				(width 0.1)
				(type default)
			)
			(layer "F.Fab")
		)
		(fp_line
			(start 0.12065 -0.3048)
			(end 0.67945 -0.3048)
			(stroke
				(width 0.1)
				(type default)
			)
			(layer "F.Fab")
		)
		(fp_line
			(start 0.12065 -0.2794)
			(end 0.12065 -0.3048)
			(stroke
				(width 0.1)
				(type default)
			)
			(layer "F.Fab")
		)
		(fp_line
			(start -0.12065 -0.2794)
			(end 0.12065 -0.2794)
			(stroke
				(width 0.1)
				(type default)
			)
			(layer "F.Fab")
		)
		(fp_line
			(start 0.120396 0.2794)
			(end -0.12065 0.2794)
			(stroke
				(width 0.1)
				(type default)
			)
			(layer "F.Fab")
		)
		(fp_line
			(start -0.12065 0.2794)
			(end -0.12065 0.3048)
			(stroke
				(width 0.1)
				(type default)
			)
			(layer "F.Fab")
		)
		(fp_line
			(start 0.67945 0.3048)
			(end 0.120396 0.3048)
			(stroke
				(width 0.1)
				(type default)
			)
			(layer "F.Fab")
		)
		(fp_line
			(start 0.120396 0.3048)
			(end 0.120396 0.2794)
			(stroke
				(width 0.1)
				(type default)
			)
			(layer "F.Fab")
		)
		(fp_line
			(start -0.12065 0.3048)
			(end -0.67945 0.3048)
			(stroke
				(width 0.1)
				(type default)
			)
			(layer "F.Fab")
		)
		(fp_line
			(start -0.67945 0.3048)
			(end -0.67945 -0.305054)
			(stroke
				(width 0.1)
				(type default)
			)
			(layer "F.Fab")
		)
		(pad "1" smd circle
			(at -0.40005 0 90)
			(size 0 0)
			(layers "F.Cu" "F.Mask" "F.Paste")
			(net "PVCCIN_CPU1")
		)
		(pad "2" smd circle
			(at 0.40005 0 90)
			(size 0 0)
			(layers "F.Cu" "F.Mask" "F.Paste")
			(net "GND")
		)
	)
	(footprint ""
		(layer "F.Cu")
		(at 331.224636 -17.414748 180)
		(property "Reference" "R2451"
			(at 0 0 180)
			(layer "F.SilkS")
			(hide yes)
			(effects
				(font
					(size 1.27 1.27)
				)
			)
		)
		(property "Value" ""
			(at 0 0 180)
			(layer "F.Fab")
			(effects
				(font
					(size 1.27 1.27)
				)
			)
		)
		(duplicate_pad_numbers_are_jumpers no)
		(fp_line
			(start 0.7874 0.4064)
			(end -0.7874 0.4064)
			(stroke
				(width 0.1524)
				(type default)
			)
			(layer "F.SilkS")
		)
		(fp_line
			(start 0.7874 -0.4064)
			(end 0.7874 0.4064)
			(stroke
				(width 0.1524)
				(type default)
			)
			(layer "F.SilkS")
		)
		(fp_line
			(start -0.7874 0.4064)
			(end -0.7874 -0.4064)
			(stroke
				(width 0.1524)
				(type default)
			)
			(layer "F.SilkS")
		)
		(fp_line
			(start -0.7874 -0.4064)
			(end 0.7874 -0.4064)
			(stroke
				(width 0.1524)
				(type default)
			)
			(layer "F.SilkS")
		)
		(fp_line
			(start 0.67945 0.3048)
			(end 0.120396 0.3048)
			(stroke
				(width 0.1)
				(type default)
			)
			(layer "F.Fab")
		)
		(fp_line
			(start 0.67945 -0.3048)
			(end 0.67945 0.3048)
			(stroke
				(width 0.1)
				(type default)
			)
			(layer "F.Fab")
		)
		(fp_line
			(start 0.12065 -0.2794)
			(end 0.12065 -0.3048)
			(stroke
				(width 0.1)
				(type default)
			)
			(layer "F.Fab")
		)
		(fp_line
			(start 0.12065 -0.3048)
			(end 0.67945 -0.3048)
			(stroke
				(width 0.1)
				(type default)
			)
			(layer "F.Fab")
		)
		(fp_line
			(start 0.120396 0.3048)
			(end 0.120396 0.2794)
			(stroke
				(width 0.1)
				(type default)
			)
			(layer "F.Fab")
		)
		(fp_line
			(start 0.120396 0.2794)
			(end -0.12065 0.2794)
			(stroke
				(width 0.1)
				(type default)
			)
			(layer "F.Fab")
		)
		(fp_line
			(start -0.12065 0.3048)
			(end -0.67945 0.3048)
			(stroke
				(width 0.1)
				(type default)
			)
			(layer "F.Fab")
		)
		(fp_line
			(start -0.12065 0.2794)
			(end -0.12065 0.3048)
			(stroke
				(width 0.1)
				(type default)
			)
			(layer "F.Fab")
		)
		(fp_line
			(start -0.12065 -0.2794)
			(end 0.12065 -0.2794)
			(stroke
				(width 0.1)
				(type default)
			)
			(layer "F.Fab")
		)
		(fp_line
			(start -0.12065 -0.305054)
			(end -0.12065 -0.2794)
			(stroke
				(width 0.1)
				(type default)
			)
			(layer "F.Fab")
		)
		(fp_line
			(start -0.67945 0.3048)
			(end -0.67945 -0.305054)
			(stroke
				(width 0.1)
				(type default)
			)
			(layer "F.Fab")
		)
		(fp_line
			(start -0.67945 -0.305054)
			(end -0.12065 -0.305054)
			(stroke
				(width 0.1)
				(type default)
			)
			(layer "F.Fab")
		)
		(pad "1" smd circle
			(at -0.40005 0 180)
			(size 0 0)
			(layers "F.Cu" "F.Mask" "F.Paste")
			(net "P3V3_AUX")
		)
		(pad "2" smd circle
			(at 0.40005 0 180)
			(size 0 0)
			(layers "F.Cu" "F.Mask" "F.Paste")
			(net "FM_ESPI_PLD_R1_EN")
		)
	)
)
